(kicad_pcb
	(version 20260206)
	(generator "pcbnew")
	(generator_version "10.0")
	(general
		(thickness 1.6)
		(legacy_teardrops no)
	)
	(paper "A4")
	(title_block
		(title "Bryce Canyon_F.DPB_16315-1-OCP.brd")
		(comment 1 "Bryce Canyon / footprints 1213-1215 of 2223")
	)
	(layers
		(0 "F.Cu" signal "TOP")
		(4 "In1.Cu" signal "L2GND")
		(6 "In2.Cu" signal "L3")
		(8 "In3.Cu" signal "L4GND")
		(10 "In4.Cu" signal "L5")
		(12 "In5.Cu" signal "L6VCC")
		(14 "In6.Cu" signal "L7VCC")
		(16 "In7.Cu" signal "L8")
		(18 "In8.Cu" signal "L9GND")
		(20 "In9.Cu" signal "L10")
		(22 "In10.Cu" signal "L11GND")
		(2 "B.Cu" signal "BOTTOM")
		(9 "F.Adhes" user "F.Adhesive")
		(11 "B.Adhes" user "B.Adhesive")
		(13 "F.Paste" user "Package Geometry/Pastemask Top")
		(15 "B.Paste" user "Package Geometry/Pastemask Bottom")
		(5 "F.SilkS" user "Ref Des/Silkscreen Top")
		(7 "B.SilkS" user "Ref Des/Silkscreen Bottom")
		(1 "F.Mask" user "Board Geometry/Soldermask Top")
		(3 "B.Mask" user "Board Geometry/Soldermask Bottom")
		(17 "Dwgs.User" user "User.Drawings")
		(19 "Cmts.User" user "User.Comments")
		(21 "Eco1.User" user "User.Eco1")
		(23 "Eco2.User" user "User.Eco2")
		(25 "Edge.Cuts" user "Board Geometry/Outline")
		(27 "Margin" user)
		(31 "F.CrtYd" user "Package Geometry/Place Bound Top")
		(29 "B.CrtYd" user "Package Geometry/Place Bound Bottom")
		(35 "F.Fab" user "Ref Des/Assembly Top")
		(33 "B.Fab" user "Ref Des/Assembly Bottom")
	)
	(footprint ""
		(layer "F.Cu")
		(at 154.399996 -287.910016 -90)
		(property "Reference" "HDDSAS4"
			(at 0 0 270)
			(layer "F.SilkS")
			(hide yes)
			(effects
				(font
					(size 1.27 1.27)
				)
			)
		)
		(property "Value" "SKT-SAS15P-14P-45-GP"
			(at -20.7645 -8.9789 270)
			(unlocked yes)
			(layer "F.Fab")
			(hide yes)
			(effects
				(font
					(size 1.016 1.016)
					(thickness 0.1524)
				)
			)
		)
		(property "Device Type" "10120818-001C-TRLF"
			(at -20.7645 -10.5029 270)
			(unlocked yes)
			(layer "F.Fab")
			(hide yes)
			(effects
				(font
					(size 1.016 1.016)
					(thickness 0.1524)
				)
			)
		)
		(duplicate_pad_numbers_are_jumpers no)
		(fp_line
			(start 1.651 4.2926)
			(end 1.651 3.0099)
			(stroke
				(width 0.1524)
				(type default)
			)
			(layer "F.SilkS")
		)
		(fp_line
			(start 8.509 4.2926)
			(end 1.651 4.2926)
			(stroke
				(width 0.1524)
				(type default)
			)
			(layer "F.SilkS")
		)
		(fp_line
			(start -23.4188 3.0099)
			(end -23.4188 -3.2512)
			(stroke
				(width 0.1524)
				(type default)
			)
			(layer "F.SilkS")
		)
		(fp_line
			(start 1.651 3.0099)
			(end -23.4188 3.0099)
			(stroke
				(width 0.1524)
				(type default)
			)
			(layer "F.SilkS")
		)
		(fp_line
			(start 8.509 3.0099)
			(end 8.509 4.2926)
			(stroke
				(width 0.1524)
				(type default)
			)
			(layer "F.SilkS")
		)
		(fp_line
			(start 23.4188 3.0099)
			(end 8.509 3.0099)
			(stroke
				(width 0.1524)
				(type default)
			)
			(layer "F.SilkS")
		)
		(fp_line
			(start -23.4188 -3.2512)
			(end 23.4188 -3.2512)
			(stroke
				(width 0.1524)
				(type default)
			)
			(layer "F.SilkS")
		)
		(fp_line
			(start 23.4188 -3.2512)
			(end 23.4188 3.0099)
			(stroke
				(width 0.1524)
				(type default)
			)
			(layer "F.SilkS")
		)
		(fp_line
			(start 15.5067 -3.3401)
			(end 16.2687 -3.3401)
			(stroke
				(width 0.3302)
				(type default)
			)
			(layer "F.SilkS")
		)
		(fp_poly
			(pts
				(xy 15.868904 -3.230372) (xy 16.503904 -3.865372) (xy 15.233904 -3.865372)
			)
			(stroke
				(width 0)
				(type default)
			)
			(fill yes)
			(layer "F.SilkS")
		)
		(fp_poly
			(pts
				(xy -22.8727 -2.7559) (xy 22.8727 -2.7559) (xy 22.8727 2.7559) (xy 8.255 2.7559) (xy 8.255 3.5179)
				(xy 1.905 3.5179) (xy 1.905 2.7559) (xy -22.8727 2.7559)
			)
			(stroke
				(width 0)
				(type default)
			)
			(fill no)
			(layer "F.CrtYd")
		)
		(fp_poly
			(pts
				(xy 1.397 4.5466) (xy 1.397 3.2639) (xy -23.6728 3.2639) (xy -23.6728 -3.5052) (xy 23.6728 -3.5052)
				(xy 23.6728 -0.00635) (xy 22.8727 -0.00635) (xy 22.8727 -2.7559) (xy -22.8727 -2.7559) (xy -22.8727 2.7559)
				(xy 1.905 2.7559) (xy 1.905 3.5179) (xy 8.255 3.5179) (xy 8.255 2.7559) (xy 22.8727 2.7559) (xy 22.8727 0.00635)
				(xy 23.6728 0.00635) (xy 23.6728 3.2639) (xy 8.763 3.2639) (xy 8.763 4.5466)
			)
			(stroke
				(width 0)
				(type default)
			)
			(fill no)
			(layer "F.CrtYd")
		)
		(fp_poly
			(pts
				(xy 1.397 4.5466) (xy 1.397 3.2639) (xy -23.6728 3.2639) (xy -23.6728 -3.5052) (xy 23.6728 -3.5052)
				(xy 23.6728 3.2639) (xy 8.763 3.2639) (xy 8.763 4.5466)
			)
			(stroke
				(width 0)
				(type default)
			)
			(fill no)
			(layer "F.Fab")
		)
		(pad "" np_thru_hole circle
			(at -18.874994 0 270)
			(size 0.254 0.254)
			(drill 1.3462)
			(layers "*.Cu" "*.Mask")
			(clearance 0.9017)
			(thermal_gap 0.9017)
		)
		(pad "" np_thru_hole circle
			(at 18.874994 0 270)
			(size 0.254 0.254)
			(drill 0.9398)
			(layers "*.Cu" "*.Mask")
			(clearance 0.6985)
			(thermal_gap 0.6985)
		)
		(pad "G1" smd rect
			(at 21.874988 0 270)
			(size 2.5908 2.5908)
			(layers "F.Cu" "F.Mask" "F.Paste")
			(net "GND")
		)
		(pad "G2" smd rect
			(at -21.874988 0 270)
			(size 2.5908 2.5908)
			(layers "F.Cu" "F.Mask" "F.Paste")
			(net "GND")
		)
		(pad "P1" smd rect
			(at 1.905 -1.82499 270)
			(size 0.6096 2.3622)
			(layers "F.Cu" "F.Mask" "F.Paste")
			(net "Net_2021")
		)
		(pad "P2" smd rect
			(at 0.635 -1.82499 270)
			(size 0.6096 2.3622)
			(layers "F.Cu" "F.Mask" "F.Paste")
			(net "Net_2022")
		)
		(pad "P3" smd rect
			(at -0.635 -1.82499 270)
			(size 0.6096 2.3622)
			(layers "F.Cu" "F.Mask" "F.Paste")
			(net "Net_2023")
		)
		(pad "P4" smd rect
			(at -1.905 -1.82499 270)
			(size 0.6096 2.3622)
			(layers "F.Cu" "F.Mask" "F.Paste")
			(net "GND")
		)
		(pad "P5" smd rect
			(at -3.175 -1.82499 270)
			(size 0.6096 2.3622)
			(layers "F.Cu" "F.Mask" "F.Paste")
			(net "HDD_PRSNT_4")
		)
		(pad "P6" smd rect
			(at -4.445 -1.82499 270)
			(size 0.6096 2.3622)
			(layers "F.Cu" "F.Mask" "F.Paste")
			(net "GND")
		)
		(pad "P7" smd rect
			(at -5.715 -1.82499 270)
			(size 0.6096 2.3622)
			(layers "F.Cu" "F.Mask" "F.Paste")
			(net "5V_PRE_4")
		)
		(pad "P8" smd rect
			(at -6.985 -1.82499 270)
			(size 0.6096 2.3622)
			(layers "F.Cu" "F.Mask" "F.Paste")
			(net "P5V_HDD4")
		)
		(pad "P9" smd rect
			(at -8.255 -1.82499 270)
			(size 0.6096 2.3622)
			(layers "F.Cu" "F.Mask" "F.Paste")
			(net "P5V_HDD4")
		)
		(pad "P10" smd rect
			(at -9.525 -1.82499 270)
			(size 0.6096 2.3622)
			(layers "F.Cu" "F.Mask" "F.Paste")
			(net "GND")
		)
		(pad "P11" smd rect
			(at -10.795 -1.82499 270)
			(size 0.6096 2.3622)
			(layers "F.Cu" "F.Mask" "F.Paste")
			(net "ACT_HDD_4")
		)
		(pad "P12" smd rect
			(at -12.065 -1.82499 270)
			(size 0.6096 2.3622)
			(layers "F.Cu" "F.Mask" "F.Paste")
			(net "GND")
		)
		(pad "P13" smd rect
			(at -13.335 -1.82499 270)
			(size 0.6096 2.3622)
			(layers "F.Cu" "F.Mask" "F.Paste")
			(net "12V_PRE_4")
		)
		(pad "P14" smd rect
			(at -14.605 -1.82499 270)
			(size 0.6096 2.3622)
			(layers "F.Cu" "F.Mask" "F.Paste")
			(net "P12V_HDD4")
		)
		(pad "P15" smd rect
			(at -15.875 -1.82499 270)
			(size 0.6096 2.3622)
			(layers "F.Cu" "F.Mask" "F.Paste")
			(net "P12V_HDD4")
		)
		(pad "S1" smd rect
			(at 15.875 -1.82499 270)
			(size 0.6096 2.3622)
			(layers "F.Cu" "F.Mask" "F.Paste")
			(net "GND")
		)
		(pad "S2" smd rect
			(at 14.605 -1.82499 270)
			(size 0.6096 2.3622)
			(layers "F.Cu" "F.Mask" "F.Paste")
			(net "SAS_HDD_RX_P4")
		)
		(pad "S3" smd rect
			(at 13.335 -1.82499 270)
			(size 0.6096 2.3622)
			(layers "F.Cu" "F.Mask" "F.Paste")
			(net "SAS_HDD_RX_N4")
		)
		(pad "S4" smd rect
			(at 12.065 -1.82499 270)
			(size 0.6096 2.3622)
			(layers "F.Cu" "F.Mask" "F.Paste")
			(net "GND")
		)
		(pad "S5" smd rect
			(at 10.795 -1.82499 270)
			(size 0.6096 2.3622)
			(layers "F.Cu" "F.Mask" "F.Paste")
			(net "PHY_DRV_A_TO_SCC_A_4_DN")
		)
		(pad "S6" smd rect
			(at 9.525 -1.82499 270)
			(size 0.6096 2.3622)
			(layers "F.Cu" "F.Mask" "F.Paste")
			(net "PHY_DRV_A_TO_SCC_A_4_DP")
		)
		(pad "S7" smd rect
			(at 8.255 -1.82499 270)
			(size 0.6096 2.3622)
			(layers "F.Cu" "F.Mask" "F.Paste")
			(net "GND")
		)
		(pad "S8" smd rect
			(at 7.480046 2.845054 270)
			(size 0.508 2.3622)
			(layers "F.Cu" "F.Mask" "F.Paste")
			(net "GND")
		)
		(pad "S9" smd rect
			(at 6.679946 2.845054 270)
			(size 0.508 2.3622)
			(layers "F.Cu" "F.Mask" "F.Paste")
			(net "Net_476")
		)
		(pad "S10" smd rect
			(at 5.8801 2.845054 270)
			(size 0.508 2.3622)
			(layers "F.Cu" "F.Mask" "F.Paste")
			(net "Net_368")
		)
		(pad "S11" smd rect
			(at 5.08 2.845054 270)
			(size 0.508 2.3622)
			(layers "F.Cu" "F.Mask" "F.Paste")
			(net "GND")
		)
		(pad "S12" smd rect
			(at 4.2799 2.845054 270)
			(size 0.508 2.3622)
			(layers "F.Cu" "F.Mask" "F.Paste")
			(net "Net_404")
		)
		(pad "S13" smd rect
			(at 3.480054 2.845054 270)
			(size 0.508 2.3622)
			(layers "F.Cu" "F.Mask" "F.Paste")
			(net "Net_440")
		)
		(pad "S14" smd rect
			(at 2.679954 2.845054 270)
			(size 0.508 2.3622)
			(layers "F.Cu" "F.Mask" "F.Paste")
			(net "GND")
		)
		(zone
			(layer "F.Cu")
			(hatch none 0.5)
			(connect_pads
				(clearance 0)
			)
			(min_thickness 0.25)
			(keepout
				(tracks not_allowed)
				(vias allowed)
				(pads allowed)
				(copperpour not_allowed)
				(footprints allowed)
			)
			(placement
				(enabled no)
				(sheetname "")
			)
			(fill
				(thermal_gap 0.5)
				(thermal_bridge_width 0.5)
				(island_removal_mode 0)
			)
			(polygon
				(pts
					(xy 158.057596 -304.648616) (xy 150.983696 -304.648616) (xy 150.983696 -311.582816) (xy 152.088596 -311.582816)
					(xy 152.088596 -307.468016) (xy 156.711396 -307.468016) (xy 156.711396 -311.582816) (xy 158.057596 -311.582816)
				)
			)
		)
		(zone
			(layer "F.Cu")
			(hatch none 0.5)
			(connect_pads
				(clearance 0)
			)
			(min_thickness 0.25)
			(keepout
				(tracks allowed)
				(vias not_allowed)
				(pads allowed)
				(copperpour not_allowed)
				(footprints allowed)
			)
			(placement
				(enabled no)
				(sheetname "")
			)
			(fill
				(thermal_gap 0.5)
				(thermal_bridge_width 0.5)
				(island_removal_mode 0)
			)
			(polygon
				(pts
					(xy 158.057596 -304.648616) (xy 150.983696 -304.648616) (xy 150.983696 -311.582816) (xy 152.088596 -311.582816)
					(xy 152.088596 -307.468016) (xy 156.711396 -307.468016) (xy 156.711396 -311.582816) (xy 158.057596 -311.582816)
				)
			)
		)
		(zone
			(layer "F.Cu")
			(hatch none 0.5)
			(connect_pads
				(clearance 0)
			)
			(min_thickness 0.25)
			(keepout
				(tracks allowed)
				(vias not_allowed)
				(pads allowed)
				(copperpour not_allowed)
				(footprints allowed)
			)
			(placement
				(enabled no)
				(sheetname "")
			)
			(fill
				(thermal_gap 0.5)
				(thermal_bridge_width 0.5)
				(island_removal_mode 0)
			)
			(polygon
				(pts
					(xy 158.057596 -271.171416) (xy 150.983696 -271.171416) (xy 150.983696 -264.237216) (xy 152.088596 -264.237216)
					(xy 152.088596 -268.352016) (xy 156.711396 -268.352016) (xy 156.711396 -264.237216) (xy 158.057596 -264.237216)
				)
			)
		)
		(zone
			(layer "F.Cu")
			(hatch none 0.5)
			(connect_pads
				(clearance 0)
			)
			(min_thickness 0.25)
			(keepout
				(tracks not_allowed)
				(vias allowed)
				(pads allowed)
				(copperpour not_allowed)
				(footprints allowed)
			)
			(placement
				(enabled no)
				(sheetname "")
			)
			(fill
				(thermal_gap 0.5)
				(thermal_bridge_width 0.5)
				(island_removal_mode 0)
			)
			(polygon
				(pts
					(xy 158.057596 -271.171416) (xy 150.983696 -271.171416) (xy 150.983696 -264.237216) (xy 152.088596 -264.237216)
					(xy 152.088596 -268.352016) (xy 156.711396 -268.352016) (xy 156.711396 -264.237216) (xy 158.057596 -264.237216)
				)
			)
		)
		(zone
			(layers "F.Cu" "B.Cu" "In1.Cu" "In2.Cu" "In3.Cu" "In4.Cu" "In5.Cu" "In6.Cu"
				"In7.Cu" "In8.Cu" "In9.Cu" "In10.Cu"
			)
			(hatch none 0.5)
			(connect_pads
				(clearance 0)
			)
			(min_thickness 0.25)
			(keepout
				(tracks not_allowed)
				(vias allowed)
				(pads allowed)
				(copperpour not_allowed)
				(footprints allowed)
			)
			(placement
				(enabled no)
				(sheetname "")
			)
			(fill
				(thermal_gap 0.5)
				(thermal_bridge_width 0.5)
				(island_removal_mode 0)
			)
			(polygon
				(pts
					(arc
						(start 155.174696 -269.035022)
						(mid 153.625296 -269.035022)
						(end 155.174696 -269.035022)
					)
				)
			)
		)
		(zone
			(layers "F.Cu" "B.Cu" "In1.Cu" "In2.Cu" "In3.Cu" "In4.Cu" "In5.Cu" "In6.Cu"
				"In7.Cu" "In8.Cu" "In9.Cu" "In10.Cu"
			)
			(hatch none 0.5)
			(connect_pads
				(clearance 0)
			)
			(min_thickness 0.25)
			(keepout
				(tracks not_allowed)
				(vias allowed)
				(pads allowed)
				(copperpour not_allowed)
				(footprints allowed)
			)
			(placement
				(enabled no)
				(sheetname "")
			)
			(fill
				(thermal_gap 0.5)
				(thermal_bridge_width 0.5)
				(island_removal_mode 0)
			)
			(polygon
				(pts
					(arc
						(start 155.377896 -306.78501)
						(mid 153.422096 -306.78501)
						(end 155.377896 -306.78501)
					)
				)
			)
		)
	)
	(footprint ""
		(layer "F.Cu")
		(at 314.898532 -127.800354 180)
		(property "Reference" "Q281"
			(at 0 0 180)
			(layer "F.SilkS")
			(hide yes)
			(effects
				(font
					(size 1.27 1.27)
				)
			)
		)
		(property "Value" "SSM3K324R-GP"
			(at 0.127 -8.9662 180)
			(unlocked yes)
			(layer "F.Fab")
			(hide yes)
			(effects
				(font
					(size 1.016 1.016)
					(thickness 0.1524)
				)
			)
		)
		(property "Device Type" "SOT23DGS2D4H35"
			(at 0.127 -10.4902 180)
			(unlocked yes)
			(layer "F.Fab")
			(hide yes)
			(effects
				(font
					(size 1.016 1.016)
					(thickness 0.1524)
				)
			)
		)
		(duplicate_pad_numbers_are_jumpers no)
		(fp_line
			(start 1.651 1.778)
			(end 1.651 -1.778)
			(stroke
				(width 0.1524)
				(type default)
			)
			(layer "F.SilkS")
		)
		(fp_line
			(start 1.651 -1.778)
			(end -1.651 -1.778)
			(stroke
				(width 0.1524)
				(type default)
			)
			(layer "F.SilkS")
		)
		(fp_line
			(start -1.651 1.778)
			(end 1.651 1.778)
			(stroke
				(width 0.1524)
				(type default)
			)
			(layer "F.SilkS")
		)
		(fp_line
			(start -1.651 -1.778)
			(end -1.651 1.778)
			(stroke
				(width 0.1524)
				(type default)
			)
			(layer "F.SilkS")
		)
		(fp_poly
			(pts
				(xy -1.778 1.8796) (xy -1.778 -1.8796) (xy 1.778 -1.8796) (xy 1.778 1.8796)
			)
			(stroke
				(width 0)
				(type default)
			)
			(fill no)
			(layer "F.CrtYd")
		)
		(fp_poly
			(pts
				(xy -1.778 1.8796) (xy -1.778 -1.8796) (xy 1.778 -1.8796) (xy 1.778 1.8796)
			)
			(stroke
				(width 0)
				(type default)
			)
			(fill no)
			(layer "F.Fab")
		)
		(pad "D" smd custom
			(at 0 -0.9525 180)
			(size 0.1905 0.1905)
			(layers "F.Cu" "F.Mask" "F.Paste")
			(net "DRV_ACT_18_N")
			(options
				(clearance outline)
				(anchor circle)
			)
			(primitives
				(gr_poly
					(pts
						(arc
							(start -0.1778 0.5715)
							(mid -0.321484 0.511984)
							(end -0.381 0.3683)
						)
						(arc
							(start -0.381 -0.3683)
							(mid -0.321484 -0.511984)
							(end -0.1778 -0.5715)
						)
						(arc
							(start 0.1778 -0.5715)
							(mid 0.321484 -0.511984)
							(end 0.381 -0.3683)
						)
						(arc
							(start 0.381 0.3683)
							(mid 0.321484 0.511984)
							(end 0.1778 0.5715)
						)
					)
					(width 0)
					(fill yes)
				)
			)
		)
		(pad "G" smd custom
			(at -0.98425 0.9525 180)
			(size 0.1905 0.1905)
			(layers "F.Cu" "F.Mask" "F.Paste")
			(net "DRIVE_A_18_ACT")
			(options
				(clearance outline)
				(anchor circle)
			)
			(primitives
				(gr_poly
					(pts
						(arc
							(start -0.1778 0.5715)
							(mid -0.321484 0.511984)
							(end -0.381 0.3683)
						)
						(arc
							(start -0.381 -0.3683)
							(mid -0.321484 -0.511984)
							(end -0.1778 -0.5715)
						)
						(arc
							(start 0.1778 -0.5715)
							(mid 0.321484 -0.511984)
							(end 0.381 -0.3683)
						)
						(arc
							(start 0.381 0.3683)
							(mid 0.321484 0.511984)
							(end 0.1778 0.5715)
						)
					)
					(width 0)
					(fill yes)
				)
			)
		)
		(pad "S" smd custom
			(at 0.98425 0.9525 180)
			(size 0.1905 0.1905)
			(layers "F.Cu" "F.Mask" "F.Paste")
			(net "GND")
			(options
				(clearance outline)
				(anchor circle)
			)
			(primitives
				(gr_poly
					(pts
						(arc
							(start -0.1778 0.5715)
							(mid -0.321484 0.511984)
							(end -0.381 0.3683)
						)
						(arc
							(start -0.381 -0.3683)
							(mid -0.321484 -0.511984)
							(end -0.1778 -0.5715)
						)
						(arc
							(start 0.1778 -0.5715)
							(mid 0.321484 -0.511984)
							(end 0.381 -0.3683)
						)
						(arc
							(start 0.381 0.3683)
							(mid 0.321484 0.511984)
							(end 0.1778 0.5715)
						)
					)
					(width 0)
					(fill yes)
				)
			)
		)
	)
	(footprint ""
		(layer "F.Cu")
		(at 449.037202 -251.16155)
		(property "Reference" "R1247"
			(at 0 0 0)
			(layer "F.SilkS")
			(hide yes)
			(effects
				(font
					(size 1.27 1.27)
				)
			)
		)
		(property "Value" "0R3J-0-U-GP"
			(at -0.0254 -2.5146 0)
			(unlocked yes)
			(layer "F.Fab")
			(hide yes)
			(effects
				(font
					(size 1.016 1.016)
					(thickness 0.1524)
				)
			)
		)
		(property "Device Type" "R603H22"
			(at -0.0254 -4.0386 0)
			(unlocked yes)
			(layer "F.Fab")
			(hide yes)
			(effects
				(font
					(size 1.016 1.016)
					(thickness 0.1524)
				)
			)
		)
		(duplicate_pad_numbers_are_jumpers no)
		(fp_line
			(start -0.4826 0)
			(end -0.2032 0)
			(stroke
				(width 0.2032)
				(type default)
			)
			(layer "F.SilkS")
		)
		(fp_line
			(start 0.2032 0)
			(end 0.4826 0)
			(stroke
				(width 0.2032)
				(type default)
			)
			(layer "F.SilkS")
		)
		(fp_rect
			(start -0.5842 1.3335)
			(end 0.5842 -1.3335)
			(stroke
				(width 0)
				(type default)
			)
			(fill no)
			(layer "F.CrtYd")
		)
		(fp_rect
			(start -0.5842 1.3335)
			(end 0.5842 -1.3335)
			(stroke
				(width 0)
				(type default)
			)
			(fill no)
			(layer "F.Fab")
		)
		(pad "1" smd custom
			(at 0 -0.762)
			(size 0.2159 0.2159)
			(layers "F.Cu" "F.Mask" "F.Paste")
			(net "P5V_C_VBST")
			(options
				(clearance outline)
				(anchor circle)
			)
			(primitives
				(gr_poly
					(pts
						(arc
							(start -0.3302 -0.4318)
							(mid -0.402042 -0.402042)
							(end -0.4318 -0.3302)
						)
						(arc
							(start -0.4318 0.3302)
							(mid -0.402042 0.402042)
							(end -0.3302 0.4318)
						)
						(arc
							(start 0.3302 0.4318)
							(mid 0.402042 0.402042)
							(end 0.4318 0.3302)
						)
						(arc
							(start 0.4318 -0.3302)
							(mid 0.402042 -0.402042)
							(end 0.3302 -0.4318)
						)
					)
					(width 0)
					(fill yes)
				)
			)
		)
		(pad "2" smd custom
			(at 0 0.762)
			(size 0.2159 0.2159)
			(layers "F.Cu" "F.Mask" "F.Paste")
			(net "P5V_C_VBST_RC")
			(options
				(clearance outline)
				(anchor circle)
			)
			(primitives
				(gr_poly
					(pts
						(arc
							(start -0.3302 -0.4318)
							(mid -0.402042 -0.402042)
							(end -0.4318 -0.3302)
						)
						(arc
							(start -0.4318 0.3302)
							(mid -0.402042 0.402042)
							(end -0.3302 0.4318)
						)
						(arc
							(start 0.3302 0.4318)
							(mid 0.402042 0.402042)
							(end 0.4318 0.3302)
						)
						(arc
							(start 0.4318 -0.3302)
							(mid 0.402042 -0.402042)
							(end 0.3302 -0.4318)
						)
					)
					(width 0)
					(fill yes)
				)
			)
		)
	)
)
